(kicad_pcb
	(version 20241229)
	(generator "pcbnew")
	(generator_version "9.0")
	(general
		(thickness 1.711)
		(legacy_teardrops no)
	)
	(paper "A4")
	(title_block
		(title "Antmicro Baseboard for Jetson AGX Thor")
		(date "2026-02-18")
		(rev "1.1.0")
		(company "Antmicro Ltd")
		(comment 1 "www.antmicro.com")
		(comment 9 "footprints 819-822 of 1170")
	)
	(layers
		(0 "F.Cu" signal)
		(4 "In1.Cu" signal)
		(6 "In2.Cu" signal)
		(8 "In3.Cu" signal)
		(10 "In4.Cu" jumper)
		(12 "In5.Cu" signal)
		(14 "In6.Cu" signal)
		(16 "In7.Cu" signal)
		(18 "In8.Cu" signal)
		(2 "B.Cu" signal)
		(9 "F.Adhes" user "F.Adhesive")
		(11 "B.Adhes" user "B.Adhesive")
		(13 "F.Paste" user)
		(15 "B.Paste" user)
		(5 "F.SilkS" user "F.Silkscreen")
		(7 "B.SilkS" user "B.Silkscreen")
		(1 "F.Mask" user)
		(3 "B.Mask" user)
		(17 "Dwgs.User" user "User.Drawings")
		(19 "Cmts.User" user "User.Comments")
		(21 "Eco1.User" user "User.Eco1")
		(23 "Eco2.User" user "User.Eco2")
		(25 "Edge.Cuts" user)
		(27 "Margin" user)
		(31 "F.CrtYd" user "F.Courtyard")
		(29 "B.CrtYd" user "B.Courtyard")
		(35 "F.Fab" user)
		(33 "B.Fab" user)
	)
	(footprint "antmicro-footprints:C_0402_1005Metric"
		(layer "B.Cu")
		(at 235.8 123)
		(descr "Capacitor SMD 0402")
		(tags "capacitor SMD 0402")
		(property "Reference" "C77"
			(at 1.08 -0.308 0)
			(layer "B.SilkS")
			(effects
				(font
					(size 0.7 0.7)
					(thickness 0.15)
				)
				(justify right top mirror)
			)
		)
		(property "Value" "C_100n_0402"
			(at -1.022927 -2.155213 0)
			(layer "B.Fab")
			(effects
				(font
					(size 0.7 0.7)
					(thickness 0.15)
				)
				(justify right top mirror)
			)
		)
		(property "Datasheet" "https://www.murata.com/products/productdetail?partno=GRM155R61H104KE14%23"
			(at 0 0 0)
			(layer "B.Fab")
			(hide yes)
			(effects
				(font
					(size 1.27 1.27)
					(thickness 0.15)
				)
				(justify mirror)
			)
		)
		(property "Description" "SMD Multilayer Ceramic Capacitor, 0.1 µF, 50 V, 0402 [1005 Metric], ± 10%, X5R, GRM Series"
			(at 0 0 0)
			(layer "B.Fab")
			(hide yes)
			(effects
				(font
					(size 1.27 1.27)
					(thickness 0.15)
				)
				(justify mirror)
			)
		)
		(property "Manufacturer" "Murata"
			(at 0 0 180)
			(unlocked yes)
			(layer "B.Fab")
			(hide yes)
			(effects
				(font
					(size 1 1)
					(thickness 0.15)
				)
				(justify mirror)
			)
		)
		(property "MPN" "GRM155R61H104KE14D"
			(at 0 0 180)
			(unlocked yes)
			(layer "B.Fab")
			(hide yes)
			(effects
				(font
					(size 1 1)
					(thickness 0.15)
				)
				(justify mirror)
			)
		)
		(property "Val" "100n"
			(at 0 0 180)
			(unlocked yes)
			(layer "B.Fab")
			(hide yes)
			(effects
				(font
					(size 1 1)
					(thickness 0.15)
				)
				(justify mirror)
			)
		)
		(property "License" "Apache-2.0"
			(at 0 0 180)
			(unlocked yes)
			(layer "B.Fab")
			(hide yes)
			(effects
				(font
					(size 1 1)
					(thickness 0.15)
				)
				(justify mirror)
			)
		)
		(property "Author" "Antmicro"
			(at 0 0 180)
			(unlocked yes)
			(layer "B.Fab")
			(hide yes)
			(effects
				(font
					(size 1 1)
					(thickness 0.15)
				)
				(justify mirror)
			)
		)
		(property "Voltage" "50V"
			(at 0 0 180)
			(unlocked yes)
			(layer "B.Fab")
			(hide yes)
			(effects
				(font
					(size 1 1)
					(thickness 0.15)
				)
				(justify mirror)
			)
		)
		(property "Dielectric" "X5R"
			(at 0 0 180)
			(unlocked yes)
			(layer "B.Fab")
			(hide yes)
			(effects
				(font
					(size 1 1)
					(thickness 0.15)
				)
				(justify mirror)
			)
		)
		(sheetname "/USB Hub/")
		(sheetfile "usb_hub.kicad_sch")
		(attr smd)
		(fp_poly
			(pts
				(xy -0.925 0.47) (xy -0.925 -0.47) (xy 0.925 -0.47) (xy 0.925 0.47)
			)
			(stroke
				(width 0.05)
				(type default)
			)
			(fill no)
			(layer "B.CrtYd")
		)
		(fp_line
			(start -0.494 -0.248)
			(end -0.494 0.25)
			(stroke
				(width 0.15)
				(type solid)
			)
			(layer "B.Fab")
		)
		(fp_line
			(start -0.494 0.25)
			(end 0.504 0.25)
			(stroke
				(width 0.15)
				(type solid)
			)
			(layer "B.Fab")
		)
		(fp_line
			(start 0.504 -0.248)
			(end -0.494 -0.248)
			(stroke
				(width 0.15)
				(type solid)
			)
			(layer "B.Fab")
		)
		(fp_line
			(start 0.504 0.25)
			(end 0.504 -0.248)
			(stroke
				(width 0.15)
				(type solid)
			)
			(layer "B.Fab")
		)
		(fp_text user "${REFERENCE}"
			(at -0.939 -4.599 0)
			(layer "B.Fab")
			(effects
				(font
					(size 0.7 0.7)
					(thickness 0.15)
				)
				(justify right top mirror)
			)
		)
		(fp_text user "License: Apache-2.0"
			(at -0.939 -5.799 0)
			(layer "B.Fab")
			(effects
				(font
					(size 0.7 0.7)
					(thickness 0.15)
				)
				(justify right top mirror)
			)
		)
		(fp_text user "Author: Antmicro"
			(at -0.939 -3.399 0)
			(layer "B.Fab")
			(effects
				(font
					(size 0.7 0.7)
					(thickness 0.15)
				)
				(justify right top mirror)
			)
		)
		(pad "1" smd roundrect
			(at -0.48 0)
			(size 0.59 0.64)
			(layers "B.Cu" "B.Mask" "B.Paste")
			(roundrect_rratio 0.25)
			(net 5 "+5V")
			(pintype "passive")
		)
		(pad "2" smd roundrect
			(at 0.48 0)
			(size 0.59 0.64)
			(layers "B.Cu" "B.Mask" "B.Paste")
			(roundrect_rratio 0.25)
			(net 1 "GND")
			(pintype "passive")
		)
	)
	(footprint "antmicro-footprints:R_0402_1005Metric"
		(layer "B.Cu")
		(at 212.8 86.66)
		(descr "Resistor SMD 0402")
		(tags "resistor SMD 0402")
		(property "Reference" "R130"
			(at -3.9 -0.3 0)
			(layer "B.SilkS")
			(effects
				(font
					(size 0.7 0.7)
					(thickness 0.15)
				)
				(justify right top mirror)
			)
		)
		(property "Value" "R_1k_0402"
			(at -1.011843 -1.772046 0)
			(layer "B.Fab")
			(effects
				(font
					(size 0.7 0.7)
					(thickness 0.15)
				)
				(justify right top mirror)
			)
		)
		(property "Datasheet" "https://www.bourns.com/docs/product-datasheets/cr.pdf"
			(at 0 0 0)
			(layer "B.Fab")
			(hide yes)
			(effects
				(font
					(size 1.27 1.27)
					(thickness 0.15)
				)
				(justify mirror)
			)
		)
		(property "Description" "SMD Chip Resistor, 1 kohm, ± 1%, 63 mW, 0402 [1005 Metric], Thick Film, General Purpose"
			(at 0 0 0)
			(layer "B.Fab")
			(hide yes)
			(effects
				(font
					(size 1.27 1.27)
					(thickness 0.15)
				)
				(justify mirror)
			)
		)
		(property "Manufacturer" "Bourns"
			(at 0 0 180)
			(unlocked yes)
			(layer "B.Fab")
			(hide yes)
			(effects
				(font
					(size 1 1)
					(thickness 0.15)
				)
				(justify mirror)
			)
		)
		(property "MPN" "CR0402-FX-1001GLF"
			(at 0 0 180)
			(unlocked yes)
			(layer "B.Fab")
			(hide yes)
			(effects
				(font
					(size 1 1)
					(thickness 0.15)
				)
				(justify mirror)
			)
		)
		(property "Val" "1k"
			(at 0 0 180)
			(unlocked yes)
			(layer "B.Fab")
			(hide yes)
			(effects
				(font
					(size 1 1)
					(thickness 0.15)
				)
				(justify mirror)
			)
		)
		(property "License" "Apache-2.0"
			(at 0 0 180)
			(unlocked yes)
			(layer "B.Fab")
			(hide yes)
			(effects
				(font
					(size 1 1)
					(thickness 0.15)
				)
				(justify mirror)
			)
		)
		(property "Author" "Antmicro"
			(at 0 0 180)
			(unlocked yes)
			(layer "B.Fab")
			(hide yes)
			(effects
				(font
					(size 1 1)
					(thickness 0.15)
				)
				(justify mirror)
			)
		)
		(property "Tolerance" "1%"
			(at 0 0 180)
			(unlocked yes)
			(layer "B.Fab")
			(hide yes)
			(effects
				(font
					(size 1 1)
					(thickness 0.15)
				)
				(justify mirror)
			)
		)
		(sheetname "/USB DP Alt mode/")
		(sheetfile "usb_dp.kicad_sch")
		(attr smd exclude_from_pos_files exclude_from_bom dnp)
		(fp_poly
			(pts
				(xy -0.925 0.47) (xy 0.925 0.47) (xy 0.925 -0.47) (xy -0.925 -0.47)
			)
			(stroke
				(width 0.05)
				(type default)
			)
			(fill no)
			(layer "B.CrtYd")
		)
		(fp_poly
			(pts
				(xy -0.5 0.25) (xy 0.5 0.25) (xy 0.5 -0.25) (xy -0.5 -0.25)
			)
			(stroke
				(width 0.15)
				(type solid)
			)
			(fill no)
			(layer "B.Fab")
		)
		(fp_text user "Author: Antmicro"
			(at -0.95 -4.169 0)
			(layer "B.Fab")
			(effects
				(font
					(size 0.7 0.7)
					(thickness 0.15)
				)
				(justify right top mirror)
			)
		)
		(fp_text user "License: Apache-2.0"
			(at -0.949999 -5.169 0)
			(layer "B.Fab")
			(effects
				(font
					(size 0.7 0.7)
					(thickness 0.15)
				)
				(justify right top mirror)
			)
		)
		(fp_text user "${REFERENCE}"
			(at -0.95 -3.168 0)
			(layer "B.Fab")
			(effects
				(font
					(size 0.7 0.7)
					(thickness 0.15)
				)
				(justify right top mirror)
			)
		)
		(pad "1" smd roundrect
			(at -0.48 0)
			(size 0.59 0.64)
			(layers "B.Cu" "B.Mask" "B.Paste")
			(roundrect_rratio 0.25)
			(net 964 "/USB DP Alt mode/USBC1_SSEQ0")
			(pintype "passive")
		)
		(pad "2" smd roundrect
			(at 0.48 0)
			(size 0.59 0.64)
			(layers "B.Cu" "B.Mask" "B.Paste")
			(roundrect_rratio 0.25)
			(net 2 "+3V3")
			(pintype "passive")
		)
	)
	(footprint "antmicro-footprints:C_0402_1005Metric"
		(layer "B.Cu")
		(at 211 60)
		(descr "Capacitor SMD 0402")
		(tags "capacitor SMD 0402")
		(property "Reference" "C160"
			(at -3.82 -0.57 0)
			(layer "B.SilkS")
			(effects
				(font
					(size 0.7 0.7)
					(thickness 0.15)
				)
				(justify right top mirror)
			)
		)
		(property "Value" "C_1u_0402"
			(at -1.022927 -2.155213 0)
			(layer "B.Fab")
			(effects
				(font
					(size 0.7 0.7)
					(thickness 0.15)
				)
				(justify right top mirror)
			)
		)
		(property "Datasheet" "https://product.tdk.com/en/search/capacitor/ceramic/mlcc/info?part_no=C1005X6S1A105K050BC"
			(at 0 0 0)
			(layer "B.Fab")
			(hide yes)
			(effects
				(font
					(size 1.27 1.27)
					(thickness 0.15)
				)
				(justify mirror)
			)
		)
		(property "Description" "SMD Multilayer Ceramic Capacitor, 1 µF, 10 V, 0402 [1005 Metric], ± 10%, X6S, C"
			(at 0 0 0)
			(layer "B.Fab")
			(hide yes)
			(effects
				(font
					(size 1.27 1.27)
					(thickness 0.15)
				)
				(justify mirror)
			)
		)
		(property "Manufacturer" "TDK"
			(at 0 0 180)
			(unlocked yes)
			(layer "B.Fab")
			(hide yes)
			(effects
				(font
					(size 1 1)
					(thickness 0.15)
				)
				(justify mirror)
			)
		)
		(property "MPN" "C1005X6S1A105K050BC"
			(at 0 0 180)
			(unlocked yes)
			(layer "B.Fab")
			(hide yes)
			(effects
				(font
					(size 1 1)
					(thickness 0.15)
				)
				(justify mirror)
			)
		)
		(property "Val" "1u"
			(at 0 0 180)
			(unlocked yes)
			(layer "B.Fab")
			(hide yes)
			(effects
				(font
					(size 1 1)
					(thickness 0.15)
				)
				(justify mirror)
			)
		)
		(property "License" "Apache-2.0"
			(at 0 0 180)
			(unlocked yes)
			(layer "B.Fab")
			(hide yes)
			(effects
				(font
					(size 1 1)
					(thickness 0.15)
				)
				(justify mirror)
			)
		)
		(property "Author" "Antmicro"
			(at 0 0 180)
			(unlocked yes)
			(layer "B.Fab")
			(hide yes)
			(effects
				(font
					(size 1 1)
					(thickness 0.15)
				)
				(justify mirror)
			)
		)
		(property "Voltage" ""
			(at 0 0 180)
			(unlocked yes)
			(layer "B.Fab")
			(hide yes)
			(effects
				(font
					(size 1 1)
					(thickness 0.15)
				)
				(justify mirror)
			)
		)
		(property "Dielectric" ""
			(at 0 0 180)
			(unlocked yes)
			(layer "B.Fab")
			(hide yes)
			(effects
				(font
					(size 1 1)
					(thickness 0.15)
				)
				(justify mirror)
			)
		)
		(sheetname "/CSI/")
		(sheetfile "csi.kicad_sch")
		(attr smd)
		(fp_rect
			(start -0.925 0.47)
			(end 0.925 -0.47)
			(stroke
				(width 0.05)
				(type default)
			)
			(fill no)
			(layer "B.CrtYd")
		)
		(fp_line
			(start -0.494 -0.248)
			(end -0.494 0.25)
			(stroke
				(width 0.15)
				(type solid)
			)
			(layer "B.Fab")
		)
		(fp_line
			(start -0.494 0.25)
			(end 0.504 0.25)
			(stroke
				(width 0.15)
				(type solid)
			)
			(layer "B.Fab")
		)
		(fp_line
			(start 0.504 -0.248)
			(end -0.494 -0.248)
			(stroke
				(width 0.15)
				(type solid)
			)
			(layer "B.Fab")
		)
		(fp_line
			(start 0.504 0.25)
			(end 0.504 -0.248)
			(stroke
				(width 0.15)
				(type solid)
			)
			(layer "B.Fab")
		)
		(fp_text user "${REFERENCE}"
			(at -0.939 -4.599 0)
			(layer "B.Fab")
			(effects
				(font
					(size 0.7 0.7)
					(thickness 0.15)
				)
				(justify right top mirror)
			)
		)
		(fp_text user "Author: Antmicro"
			(at -0.939 -3.399 0)
			(layer "B.Fab")
			(effects
				(font
					(size 0.7 0.7)
					(thickness 0.15)
				)
				(justify right top mirror)
			)
		)
		(fp_text user "License: Apache-2.0"
			(at -0.939 -5.799 0)
			(layer "B.Fab")
			(effects
				(font
					(size 0.7 0.7)
					(thickness 0.15)
				)
				(justify right top mirror)
			)
		)
		(pad "1" smd roundrect
			(at -0.48 0)
			(size 0.59 0.64)
			(layers "B.Cu" "B.Mask" "B.Paste")
			(roundrect_rratio 0.25)
			(net 1 "GND")
			(pintype "passive")
		)
		(pad "2" smd roundrect
			(at 0.48 0)
			(size 0.59 0.64)
			(layers "B.Cu" "B.Mask" "B.Paste")
			(roundrect_rratio 0.25)
			(net 8 "/CSI/CSIB_3V3")
			(pintype "passive")
		)
	)
	(footprint "antmicro-footprints:C_0402_1005Metric"
		(layer "B.Cu")
		(at 94 121.775 180)
		(descr "Capacitor SMD 0402")
		(tags "capacitor SMD 0402")
		(property "Reference" "C212"
			(at -3.8 -0.625 0)
			(layer "B.SilkS")
			(effects
				(font
					(size 0.7 0.7)
					(thickness 0.15)
				)
				(justify left bottom mirror)
			)
		)
		(property "Value" "C_220n_0402"
			(at -1.022927 -2.155213 0)
			(layer "B.Fab")
			(effects
				(font
					(size 0.7 0.7)
					(thickness 0.15)
				)
				(justify left bottom mirror)
			)
		)
		(property "Datasheet" "https://www.yageo.com/en/Chart/Download/pdf/CC0402KRX5R6BB224"
			(at 0 0 0)
			(layer "B.Fab")
			(hide yes)
			(effects
				(font
					(size 1.27 1.27)
					(thickness 0.15)
				)
				(justify mirror)
			)
		)
		(property "Description" "SMD Multilayer Ceramic Capacitor, 0.22 µF, 10 V, 0402 [1005 Metric], ± 10%, X5R, CC Series"
			(at 0 0 0)
			(layer "B.Fab")
			(hide yes)
			(effects
				(font
					(size 1.27 1.27)
					(thickness 0.15)
				)
				(justify mirror)
			)
		)
		(property "MPN" "CC0402KRX5R6BB224"
			(at 0 0 180)
			(unlocked yes)
			(layer "B.Fab")
			(hide yes)
			(effects
				(font
					(size 1 1)
					(thickness 0.15)
				)
				(justify mirror)
			)
		)
		(property "Val" "220n"
			(at 0 0 180)
			(unlocked yes)
			(layer "B.Fab")
			(hide yes)
			(effects
				(font
					(size 1 1)
					(thickness 0.15)
				)
				(justify mirror)
			)
		)
		(property "Voltage" "25V"
			(at 0 0 180)
			(unlocked yes)
			(layer "B.Fab")
			(hide yes)
			(effects
				(font
					(size 1 1)
					(thickness 0.15)
				)
				(justify mirror)
			)
		)
		(property "Dielectric" "X7R"
			(at 0 0 180)
			(unlocked yes)
			(layer "B.Fab")
			(hide yes)
			(effects
				(font
					(size 1 1)
					(thickness 0.15)
				)
				(justify mirror)
			)
		)
		(property "Manufacturer" "YAGEO"
			(at 0 0 180)
			(unlocked yes)
			(layer "B.Fab")
			(hide yes)
			(effects
				(font
					(size 1 1)
					(thickness 0.15)
				)
				(justify mirror)
			)
		)
		(property "License" "Apache-2.0"
			(at 0 0 180)
			(unlocked yes)
			(layer "B.Fab")
			(hide yes)
			(effects
				(font
					(size 1 1)
					(thickness 0.15)
				)
				(justify mirror)
			)
		)
		(property "Author" "Antmicro"
			(at 0 0 180)
			(unlocked yes)
			(layer "B.Fab")
			(hide yes)
			(effects
				(font
					(size 1 1)
					(thickness 0.15)
				)
				(justify mirror)
			)
		)
		(property "Public" "False"
			(at 0 0 180)
			(unlocked yes)
			(layer "B.Fab")
			(hide yes)
			(effects
				(font
					(size 1 1)
					(thickness 0.15)
				)
				(justify mirror)
			)
		)
		(sheetname "/Expansion connector/")
		(sheetfile "expansion_connector.kicad_sch")
		(attr smd)
		(fp_poly
			(pts
				(xy -0.925 0.47) (xy 0.925 0.47) (xy 0.925 -0.47) (xy -0.925 -0.47)
			)
			(stroke
				(width 0.05)
				(type default)
			)
			(fill no)
			(layer "B.CrtYd")
		)
		(fp_line
			(start 0.504 0.25)
			(end 0.504 -0.248)
			(stroke
				(width 0.15)
				(type solid)
			)
			(layer "B.Fab")
		)
		(fp_line
			(start 0.504 -0.248)
			(end -0.494 -0.248)
			(stroke
				(width 0.15)
				(type solid)
			)
			(layer "B.Fab")
		)
		(fp_line
			(start -0.494 0.25)
			(end 0.504 0.25)
			(stroke
				(width 0.15)
				(type solid)
			)
			(layer "B.Fab")
		)
		(fp_line
			(start -0.494 -0.248)
			(end -0.494 0.25)
			(stroke
				(width 0.15)
				(type solid)
			)
			(layer "B.Fab")
		)
		(fp_text user "${REFERENCE}"
			(at -0.939 -4.599 0)
			(layer "B.Fab")
			(effects
				(font
					(size 0.7 0.7)
					(thickness 0.15)
				)
				(justify left bottom mirror)
			)
		)
		(fp_text user "License: Apache-2.0"
			(at -0.939 -5.799 0)
			(layer "B.Fab")
			(effects
				(font
					(size 0.7 0.7)
					(thickness 0.15)
				)
				(justify left bottom mirror)
			)
		)
		(fp_text user "Author: Antmicro"
			(at -0.939 -3.399 0)
			(layer "B.Fab")
			(effects
				(font
					(size 0.7 0.7)
					(thickness 0.15)
				)
				(justify left bottom mirror)
			)
		)
		(pad "1" smd roundrect
			(at -0.48 0 180)
			(size 0.59 0.64)
			(layers "B.Cu" "B.Mask" "B.Paste")
			(roundrect_rratio 0.25)
			(net 519 "/Expansion connector/PCIe_{C3x2}.TX1-")
			(pintype "passive")
		)
		(pad "2" smd roundrect
			(at 0.48 0 180)
			(size 0.59 0.64)
			(layers "B.Cu" "B.Mask" "B.Paste")
			(roundrect_rratio 0.25)
			(net 475 "/Expansion connector/PET1_C3_P")
			(pintype "passive")
		)
	)
)
